# S9S_MB_2U (Grand Teton) — schematic netlist excerpt (pin names and nets, part order shuffled) for the footprints in the layout excerpt that follows; sources: Cadence DE-HDL packaged netlist, KiCad conversion of 03242023_DA0F0TMBIJ0_F0T_Motherboard_J_brd_V01_OCP.brd

C1939  Q_CAP  10UF 6.3V 20% X6S  pkg C0402  page 217 : A = P3V3_AUX_FPGA_VCCIO1 ; B = GND
PR451  Q_RES  10K 1% EMPTY  pkg 0402LF  page 266 : A = PVCCFA_EHV_FIVRA_CPU0_BTSEN ; B = GND

(kicad_pcb
	(version 20260206)
	(generator "pcbnew")
	(generator_version "10.0")
	(general
		(thickness 1.6)
		(legacy_teardrops no)
	)
	(paper "A4")
	(title_block
		(title "03242023_DA0F0TMBIJ0_F0T_Motherboard_J_brd_V01_OCP.brd")
		(comment 1 "Grand Teton / footprints 5451-5452 of 6105")
	)
	(layers
		(0 "F.Cu" signal "TOP")
		(4 "In1.Cu" signal "GND")
		(6 "In2.Cu" signal "IN1")
		(8 "In3.Cu" signal "GND1")
		(10 "In4.Cu" signal "IN2")
		(12 "In5.Cu" signal "GND2")
		(14 "In6.Cu" signal "IN3")
		(16 "In7.Cu" signal "GND3")
		(18 "In8.Cu" signal "VCC")
		(20 "In9.Cu" signal "VCC1")
		(22 "In10.Cu" signal "GND4")
		(24 "In11.Cu" signal "IN4")
		(26 "In12.Cu" signal "GND5")
		(28 "In13.Cu" signal "IN5")
		(30 "In14.Cu" signal "GND6")
		(32 "In15.Cu" signal "IN6")
		(34 "In16.Cu" signal "GND7")
		(2 "B.Cu" signal "BOTTOM")
		(9 "F.Adhes" user "F.Adhesive")
		(11 "B.Adhes" user "B.Adhesive")
		(13 "F.Paste" user "Package Geometry/Pastemask Top")
		(15 "B.Paste" user "Package Geometry/Pastemask Bottom")
		(5 "F.SilkS" user "Ref Des/Silkscreen Top")
		(7 "B.SilkS" user "Ref Des/Silkscreen Bottom")
		(1 "F.Mask" user "Board Geometry/Soldermask Top")
		(3 "B.Mask" user "Board Geometry/Soldermask Bottom")
		(17 "Dwgs.User" user "User.Drawings")
		(19 "Cmts.User" user "User.Comments")
		(21 "Eco1.User" user "User.Eco1")
		(23 "Eco2.User" user "User.Eco2")
		(25 "Edge.Cuts" user "Board Geometry/Outline")
		(27 "Margin" user)
		(31 "F.CrtYd" user "Package Geometry/Place Bound Top")
		(29 "B.CrtYd" user "Package Geometry/Place Bound Bottom")
		(35 "F.Fab" user "Ref Des/Assembly Top")
		(33 "B.Fab" user "Ref Des/Assembly Bottom")
	)
	(footprint ""
		(layer "B.Cu")
		(at 175.44288 -123.948698 -90)
		(property "Reference" "C1939"
			(at 0 0 90)
			(layer "B.SilkS")
			(hide yes)
			(effects
				(font
					(size 1.27 1.27)
				)
				(justify mirror)
			)
		)
		(property "Value" ""
			(at 0 0 90)
			(layer "B.Fab")
			(effects
				(font
					(size 1.27 1.27)
				)
				(justify mirror)
			)
		)
		(duplicate_pad_numbers_are_jumpers no)
		(fp_line
			(start -0.7874 0.4064)
			(end 0.7874 0.4064)
			(stroke
				(width 0.1524)
				(type default)
			)
			(layer "B.SilkS")
		)
		(fp_line
			(start 0.7874 0.4064)
			(end 0.7874 -0.4064)
			(stroke
				(width 0.1524)
				(type default)
			)
			(layer "B.SilkS")
		)
		(fp_line
			(start -0.7874 -0.4064)
			(end -0.7874 0.4064)
			(stroke
				(width 0.1524)
				(type default)
			)
			(layer "B.SilkS")
		)
		(fp_line
			(start 0.7874 -0.4064)
			(end -0.7874 -0.4064)
			(stroke
				(width 0.1524)
				(type default)
			)
			(layer "B.SilkS")
		)
		(fp_line
			(start -0.67945 0.3048)
			(end -0.120396 0.3048)
			(stroke
				(width 0.1)
				(type default)
			)
			(layer "B.Fab")
		)
		(fp_line
			(start -0.120396 0.3048)
			(end -0.120396 0.2794)
			(stroke
				(width 0.1)
				(type default)
			)
			(layer "B.Fab")
		)
		(fp_line
			(start 0.12065 0.3048)
			(end 0.67945 0.3048)
			(stroke
				(width 0.1)
				(type default)
			)
			(layer "B.Fab")
		)
		(fp_line
			(start 0.67945 0.3048)
			(end 0.67945 -0.305054)
			(stroke
				(width 0.1)
				(type default)
			)
			(layer "B.Fab")
		)
		(fp_line
			(start -0.120396 0.2794)
			(end 0.12065 0.2794)
			(stroke
				(width 0.1)
				(type default)
			)
			(layer "B.Fab")
		)
		(fp_line
			(start 0.12065 0.2794)
			(end 0.12065 0.3048)
			(stroke
				(width 0.1)
				(type default)
			)
			(layer "B.Fab")
		)
		(fp_line
			(start -0.12065 -0.2794)
			(end -0.12065 -0.3048)
			(stroke
				(width 0.1)
				(type default)
			)
			(layer "B.Fab")
		)
		(fp_line
			(start 0.12065 -0.2794)
			(end -0.12065 -0.2794)
			(stroke
				(width 0.1)
				(type default)
			)
			(layer "B.Fab")
		)
		(fp_line
			(start -0.67945 -0.3048)
			(end -0.67945 0.3048)
			(stroke
				(width 0.1)
				(type default)
			)
			(layer "B.Fab")
		)
		(fp_line
			(start -0.12065 -0.3048)
			(end -0.67945 -0.3048)
			(stroke
				(width 0.1)
				(type default)
			)
			(layer "B.Fab")
		)
		(fp_line
			(start 0.12065 -0.305054)
			(end 0.12065 -0.2794)
			(stroke
				(width 0.1)
				(type default)
			)
			(layer "B.Fab")
		)
		(fp_line
			(start 0.67945 -0.305054)
			(end 0.12065 -0.305054)
			(stroke
				(width 0.1)
				(type default)
			)
			(layer "B.Fab")
		)
		(pad "1" smd circle
			(at 0.40005 0 90)
			(size 0 0)
			(layers "B.Cu" "B.Mask" "B.Paste")
			(net "P3V3_AUX_FPGA_VCCIO1")
		)
		(pad "2" smd circle
			(at -0.40005 0 90)
			(size 0 0)
			(layers "B.Cu" "B.Mask" "B.Paste")
			(net "GND")
		)
	)
	(footprint ""
		(layer "B.Cu")
		(at 359.43032 -358.522016)
		(property "Reference" "PR451"
			(at 0 0 0)
			(layer "B.SilkS")
			(hide yes)
			(effects
				(font
					(size 1.27 1.27)
				)
				(justify mirror)
			)
		)
		(property "Value" ""
			(at 0 0 0)
			(layer "B.Fab")
			(effects
				(font
					(size 1.27 1.27)
				)
				(justify mirror)
			)
		)
		(duplicate_pad_numbers_are_jumpers no)
		(fp_line
			(start -0.7874 -0.4064)
			(end -0.7874 0.4064)
			(stroke
				(width 0.1524)
				(type default)
			)
			(layer "B.SilkS")
		)
		(fp_line
			(start -0.7874 0.4064)
			(end 0.7874 0.4064)
			(stroke
				(width 0.1524)
				(type default)
			)
			(layer "B.SilkS")
		)
		(fp_line
			(start 0.7874 -0.4064)
			(end -0.7874 -0.4064)
			(stroke
				(width 0.1524)
				(type default)
			)
			(layer "B.SilkS")
		)
		(fp_line
			(start 0.7874 0.4064)
			(end 0.7874 -0.4064)
			(stroke
				(width 0.1524)
				(type default)
			)
			(layer "B.SilkS")
		)
		(fp_line
			(start -0.67945 -0.3048)
			(end -0.67945 0.3048)
			(stroke
				(width 0.1)
				(type default)
			)
			(layer "B.Fab")
		)
		(fp_line
			(start -0.67945 0.3048)
			(end -0.120396 0.3048)
			(stroke
				(width 0.1)
				(type default)
			)
			(layer "B.Fab")
		)
		(fp_line
			(start -0.12065 -0.3048)
			(end -0.67945 -0.3048)
			(stroke
				(width 0.1)
				(type default)
			)
			(layer "B.Fab")
		)
		(fp_line
			(start -0.12065 -0.2794)
			(end -0.12065 -0.3048)
			(stroke
				(width 0.1)
				(type default)
			)
			(layer "B.Fab")
		)
		(fp_line
			(start -0.120396 0.2794)
			(end 0.12065 0.2794)
			(stroke
				(width 0.1)
				(type default)
			)
			(layer "B.Fab")
		)
		(fp_line
			(start -0.120396 0.3048)
			(end -0.120396 0.2794)
			(stroke
				(width 0.1)
				(type default)
			)
			(layer "B.Fab")
		)
		(fp_line
			(start 0.12065 -0.305054)
			(end 0.12065 -0.2794)
			(stroke
				(width 0.1)
				(type default)
			)
			(layer "B.Fab")
		)
		(fp_line
			(start 0.12065 -0.2794)
			(end -0.12065 -0.2794)
			(stroke
				(width 0.1)
				(type default)
			)
			(layer "B.Fab")
		)
		(fp_line
			(start 0.12065 0.2794)
			(end 0.12065 0.3048)
			(stroke
				(width 0.1)
				(type default)
			)
			(layer "B.Fab")
		)
		(fp_line
			(start 0.12065 0.3048)
			(end 0.67945 0.3048)
			(stroke
				(width 0.1)
				(type default)
			)
			(layer "B.Fab")
		)
		(fp_line
			(start 0.67945 -0.305054)
			(end 0.12065 -0.305054)
			(stroke
				(width 0.1)
				(type default)
			)
			(layer "B.Fab")
		)
		(fp_line
			(start 0.67945 0.3048)
			(end 0.67945 -0.305054)
			(stroke
				(width 0.1)
				(type default)
			)
			(layer "B.Fab")
		)
		(pad "1" smd circle
			(at 0.40005 0 180)
			(size 0 0)
			(layers "B.Cu" "B.Mask" "B.Paste")
			(net "PVCCFA_EHV_FIVRA_CPU0_BTSEN")
		)
		(pad "2" smd circle
			(at -0.40005 0 180)
			(size 0 0)
			(layers "B.Cu" "B.Mask" "B.Paste")
			(net "GND")
		)
	)
)
